(kicad_pcb
	(version 20260206)
	(generator "pcbnew")
	(generator_version "10.0")
	(general
		(thickness 1.6)
		(legacy_teardrops no)
	)
	(paper "A4")
	(title_block
		(title "Wiwynn_Tioga_Pass_MB.brd")
		(comment 1 "Tioga Pass / footprints 1352-1356 of 4770")
	)
	(layers
		(0 "F.Cu" signal "TOP")
		(4 "In1.Cu" signal "L2GND")
		(6 "In2.Cu" signal "L3")
		(8 "In3.Cu" signal "L4GND")
		(10 "In4.Cu" signal "L5")
		(12 "In5.Cu" signal "L6GND")
		(14 "In6.Cu" signal "L7VCC")
		(16 "In7.Cu" signal "L8VCC")
		(18 "In8.Cu" signal "L9GND")
		(20 "In9.Cu" signal "L10")
		(22 "In10.Cu" signal "L11GND")
		(24 "In11.Cu" signal "L12")
		(26 "In12.Cu" signal "L13GND")
		(2 "B.Cu" signal "BOTTOM")
		(9 "F.Adhes" user "F.Adhesive")
		(11 "B.Adhes" user "B.Adhesive")
		(13 "F.Paste" user "Package Geometry/Pastemask Top")
		(15 "B.Paste" user "Package Geometry/Pastemask Bottom")
		(5 "F.SilkS" user "Ref Des/Silkscreen Top")
		(7 "B.SilkS" user "Ref Des/Silkscreen Bottom")
		(1 "F.Mask" user "Board Geometry/Soldermask Top")
		(3 "B.Mask" user "Board Geometry/Soldermask Bottom")
		(17 "Dwgs.User" user "User.Drawings")
		(19 "Cmts.User" user "User.Comments")
		(21 "Eco1.User" user "User.Eco1")
		(23 "Eco2.User" user "User.Eco2")
		(25 "Edge.Cuts" user "Board Geometry/Outline")
		(27 "Margin" user)
		(31 "F.CrtYd" user "Package Geometry/Place Bound Top")
		(29 "B.CrtYd" user "Package Geometry/Place Bound Bottom")
		(35 "F.Fab" user "Ref Des/Assembly Top")
		(33 "B.Fab" user "Ref Des/Assembly Bottom")
	)
	(footprint ""
		(layer "F.Cu")
		(at 391.2616 -140.2588 90)
		(property "Reference" "C8A15"
			(at 2.92862 3.24612 0)
			(unlocked yes)
			(layer "F.SilkS")
			(effects
				(font
					(size 0.4064 0.254)
					(thickness 0.1524)
				)
			)
		)
		(property "Value" ""
			(at 0 0 90)
			(layer "F.Fab")
			(effects
				(font
					(size 1.27 1.27)
				)
			)
		)
		(duplicate_pad_numbers_are_jumpers no)
		(fp_line
			(start 2.504948 -1.616456)
			(end 2.504948 1.633728)
			(stroke
				(width 0.1524)
				(type default)
			)
			(layer "F.SilkS")
		)
		(fp_line
			(start 1.6002 -1.616456)
			(end 2.504948 -1.616456)
			(stroke
				(width 0.1524)
				(type default)
			)
			(layer "F.SilkS")
		)
		(fp_line
			(start -1.6002 -1.616456)
			(end -2.563114 -1.616456)
			(stroke
				(width 0.1524)
				(type default)
			)
			(layer "F.SilkS")
		)
		(fp_line
			(start -2.563114 -1.616456)
			(end -2.563114 1.633728)
			(stroke
				(width 0.1524)
				(type default)
			)
			(layer "F.SilkS")
		)
		(fp_line
			(start 2.504948 1.633728)
			(end 1.6002 1.633728)
			(stroke
				(width 0.1524)
				(type default)
			)
			(layer "F.SilkS")
		)
		(fp_line
			(start -2.563114 1.633728)
			(end -1.6002 1.633728)
			(stroke
				(width 0.1524)
				(type default)
			)
			(layer "F.SilkS")
		)
		(fp_line
			(start 2.286 7.366)
			(end 2.286 1.63195)
			(stroke
				(width 0.1524)
				(type default)
			)
			(layer "F.SilkS")
		)
		(fp_line
			(start 2.286 7.366)
			(end 1.600708 7.366)
			(stroke
				(width 0.1524)
				(type default)
			)
			(layer "F.SilkS")
		)
		(fp_line
			(start -2.286 7.366)
			(end -2.286 1.632712)
			(stroke
				(width 0.1524)
				(type default)
			)
			(layer "F.SilkS")
		)
		(fp_line
			(start -2.286 7.366)
			(end -1.60147 7.366)
			(stroke
				(width 0.1524)
				(type default)
			)
			(layer "F.SilkS")
		)
		(fp_rect
			(start -2.286 7.366)
			(end 2.286 -0.254)
			(stroke
				(width 0)
				(type default)
			)
			(fill no)
			(layer "F.CrtYd")
		)
		(fp_line
			(start 2.286 -0.254)
			(end 2.286 7.366)
			(stroke
				(width 0.1)
				(type default)
			)
			(layer "F.Fab")
		)
		(fp_line
			(start -2.286 -0.254)
			(end 2.286 -0.254)
			(stroke
				(width 0.1)
				(type default)
			)
			(layer "F.Fab")
		)
		(fp_line
			(start 2.286 7.366)
			(end -2.286 7.366)
			(stroke
				(width 0.1)
				(type default)
			)
			(layer "F.Fab")
		)
		(fp_line
			(start -2.286 7.366)
			(end -2.286 -0.254)
			(stroke
				(width 0.1)
				(type default)
			)
			(layer "F.Fab")
		)
		(pad "1" smd rect
			(at 0 0 90)
			(size 2.54 3.048)
			(layers "F.Cu" "F.Mask" "F.Paste")
			(net "P1V05_PCH_STBY")
		)
		(pad "2" smd rect
			(at 0 7.112 90)
			(size 2.54 3.048)
			(layers "F.Cu" "F.Mask" "F.Paste")
			(net "GND")
		)
	)
	(footprint ""
		(layer "F.Cu")
		(at 11.502644 5.004562 -90)
		(property "Reference" "R12W15"
			(at 0 0 270)
			(layer "F.SilkS")
			(hide yes)
			(effects
				(font
					(size 1.27 1.27)
				)
			)
		)
		(property "Value" "*"
			(at 0.064008 -4.108196 270)
			(unlocked yes)
			(layer "F.Fab")
			(hide yes)
			(effects
				(font
					(size 1.27 1.016)
					(thickness 0.1524)
				)
			)
		)
		(property "Device Type" "665KR2B-GP_SMD-RG2-665KR2B-GP,A"
			(at 0.064008 -5.632196 270)
			(unlocked yes)
			(layer "F.Fab")
			(hide yes)
			(effects
				(font
					(size 1.27 1.016)
					(thickness 0.1524)
				)
			)
		)
		(duplicate_pad_numbers_are_jumpers no)
		(fp_line
			(start -0.508 -0.9398)
			(end -0.508 0.9398)
			(stroke
				(width 0.1524)
				(type default)
			)
			(layer "F.SilkS")
		)
		(fp_line
			(start 0.508 -0.9398)
			(end -0.508 -0.9398)
			(stroke
				(width 0.1524)
				(type default)
			)
			(layer "F.SilkS")
		)
		(fp_rect
			(start -0.508 0.9398)
			(end 0.508 -0.9398)
			(stroke
				(width 0)
				(type default)
			)
			(fill no)
			(layer "F.CrtYd")
		)
		(fp_rect
			(start -0.508 0.9398)
			(end 0.508 -0.9398)
			(stroke
				(width 0)
				(type default)
			)
			(fill no)
			(layer "F.Fab")
		)
		(pad "1" smd custom
			(at 0 -0.4445 270)
			(size 0.1397 0.1397)
			(layers "F.Cu" "F.Mask" "F.Paste")
			(net "VR_PVDDQ_GHJ_AIINSEN")
			(options
				(clearance outline)
				(anchor circle)
			)
			(primitives
				(gr_poly
					(pts
						(arc
							(start -0.1778 -0.2794)
							(mid -0.249642 -0.249642)
							(end -0.2794 -0.1778)
						)
						(arc
							(start -0.2794 0.1778)
							(mid -0.249642 0.249642)
							(end -0.1778 0.2794)
						)
						(arc
							(start 0.1778 0.2794)
							(mid 0.249642 0.249642)
							(end 0.2794 0.1778)
						)
						(arc
							(start 0.2794 -0.1778)
							(mid 0.249642 -0.249642)
							(end 0.1778 -0.2794)
						)
					)
					(width 0)
					(fill yes)
				)
			)
		)
		(pad "2" smd custom
			(at 0 0.4445 270)
			(size 0.1397 0.1397)
			(layers "F.Cu" "F.Mask" "F.Paste")
			(net "VR_PVDDQ_GHJ_VINSEN")
			(options
				(clearance outline)
				(anchor circle)
			)
			(primitives
				(gr_poly
					(pts
						(arc
							(start -0.1778 -0.2794)
							(mid -0.249642 -0.249642)
							(end -0.2794 -0.1778)
						)
						(arc
							(start -0.2794 0.1778)
							(mid -0.249642 0.249642)
							(end -0.1778 0.2794)
						)
						(arc
							(start 0.1778 0.2794)
							(mid 0.249642 0.249642)
							(end 0.2794 0.1778)
						)
						(arc
							(start 0.2794 -0.1778)
							(mid 0.249642 -0.249642)
							(end 0.1778 -0.2794)
						)
					)
					(width 0)
					(fill yes)
				)
			)
		)
	)
	(footprint ""
		(layer "F.Cu")
		(at 1.133094 -123.20905 90)
		(property "Reference" "CF22"
			(at 0 0 90)
			(layer "F.SilkS")
			(hide yes)
			(effects
				(font
					(size 1.27 1.27)
				)
			)
		)
		(property "Value" "*"
			(at 1.1811 -2.8194 90)
			(unlocked yes)
			(layer "F.Fab")
			(hide yes)
			(effects
				(font
					(size 1.27 1.016)
					(thickness 0.1524)
				)
			)
		)
		(property "Device Type" "SC22P50V2JN-4GP_SMD-BCG-SC22P5A"
			(at 1.1811 -4.3434 90)
			(unlocked yes)
			(layer "F.Fab")
			(hide yes)
			(effects
				(font
					(size 1.27 1.016)
					(thickness 0.1524)
				)
			)
		)
		(duplicate_pad_numbers_are_jumpers no)
		(fp_rect
			(start -0.4318 0.9525)
			(end 0.4318 -0.9525)
			(stroke
				(width 0)
				(type default)
			)
			(fill no)
			(layer "F.CrtYd")
		)
		(fp_rect
			(start -0.4318 0.9525)
			(end 0.4318 -0.9525)
			(stroke
				(width 0)
				(type default)
			)
			(fill no)
			(layer "F.Fab")
		)
		(pad "1" smd custom
			(at 0 -0.4445 90)
			(size 0.1524 0.1524)
			(layers "F.Cu" "F.Mask" "F.Paste")
			(net "VR_PVDDQ_KLM_AIREF2")
			(options
				(clearance outline)
				(anchor circle)
			)
			(primitives
				(gr_poly
					(pts
						(arc
							(start 0.3048 -0.2032)
							(mid 0.275042 -0.275042)
							(end 0.2032 -0.3048)
						)
						(arc
							(start -0.2032 -0.3048)
							(mid -0.275042 -0.275042)
							(end -0.3048 -0.2032)
						)
						(arc
							(start -0.3048 0.2032)
							(mid -0.275042 0.275042)
							(end -0.2032 0.3048)
						)
						(arc
							(start 0.2032 0.3048)
							(mid 0.275042 0.275042)
							(end 0.3048 0.2032)
						)
					)
					(width 0)
					(fill yes)
				)
			)
		)
		(pad "2" smd custom
			(at 0 0.4445 90)
			(size 0.1524 0.1524)
			(layers "F.Cu" "F.Mask" "F.Paste")
			(net "ISENSE_PVDDQ_KLM_PH2_IMON")
			(options
				(clearance outline)
				(anchor circle)
			)
			(primitives
				(gr_poly
					(pts
						(arc
							(start 0.3048 -0.2032)
							(mid 0.275042 -0.275042)
							(end 0.2032 -0.3048)
						)
						(arc
							(start -0.2032 -0.3048)
							(mid -0.275042 -0.275042)
							(end -0.3048 -0.2032)
						)
						(arc
							(start -0.3048 0.2032)
							(mid -0.275042 0.275042)
							(end -0.2032 0.3048)
						)
						(arc
							(start 0.2032 0.3048)
							(mid 0.275042 0.275042)
							(end 0.3048 0.2032)
						)
					)
					(width 0)
					(fill yes)
				)
			)
		)
	)
	(footprint ""
		(layer "F.Cu")
		(at 386.1054 -0.254)
		(property "Reference" "R7G17"
			(at 0 0 0)
			(layer "F.SilkS")
			(hide yes)
			(effects
				(font
					(size 1.27 1.27)
				)
			)
		)
		(property "Value" ""
			(at 0 0 0)
			(layer "F.Fab")
			(effects
				(font
					(size 1.27 1.27)
				)
			)
		)
		(duplicate_pad_numbers_are_jumpers no)
		(fp_poly
			(pts
				(xy -0.2794 -0.1016) (xy 0.2794 -0.1016) (xy 0.2794 0.9906) (xy -0.2794 0.9906)
			)
			(stroke
				(width 0)
				(type default)
			)
			(fill no)
			(layer "F.CrtYd")
		)
		(fp_line
			(start -0.2794 -0.1016)
			(end -0.2794 0.9906)
			(stroke
				(width 0.1)
				(type default)
			)
			(layer "F.Fab")
		)
		(fp_line
			(start -0.2794 0.9906)
			(end 0.2794 0.9906)
			(stroke
				(width 0.1)
				(type default)
			)
			(layer "F.Fab")
		)
		(fp_line
			(start 0.2794 -0.1016)
			(end -0.2794 -0.1016)
			(stroke
				(width 0.1)
				(type default)
			)
			(layer "F.Fab")
		)
		(fp_line
			(start 0.2794 0.9906)
			(end 0.2794 -0.1016)
			(stroke
				(width 0.1)
				(type default)
			)
			(layer "F.Fab")
		)
		(pad "1" smd rect
			(at 0 0)
			(size 0.508 0.508)
			(layers "F.Cu" "F.Mask" "F.Paste")
			(net "JTAG_BMC_TDO")
		)
		(pad "2" smd rect
			(at 0 0.889)
			(size 0.508 0.508)
			(layers "F.Cu" "F.Mask" "F.Paste")
			(net "JTAG_TDO")
		)
		(zone
			(layer "F.Cu")
			(hatch none 0.5)
			(connect_pads
				(clearance 0)
			)
			(min_thickness 0.25)
			(keepout
				(tracks allowed)
				(vias not_allowed)
				(pads allowed)
				(copperpour not_allowed)
				(footprints allowed)
			)
			(placement
				(enabled no)
				(sheetname "")
			)
			(fill
				(thermal_gap 0.5)
				(thermal_bridge_width 0.5)
				(island_removal_mode 0)
			)
			(polygon
				(pts
					(xy 385.8514 0) (xy 386.3594 0) (xy 386.3594 0.381) (xy 385.8514 0.381)
				)
			)
		)
		(zone
			(layer "F.Cu")
			(hatch none 0.5)
			(connect_pads
				(clearance 0)
			)
			(min_thickness 0.25)
			(keepout
				(tracks not_allowed)
				(vias allowed)
				(pads allowed)
				(copperpour not_allowed)
				(footprints allowed)
			)
			(placement
				(enabled no)
				(sheetname "")
			)
			(fill
				(thermal_gap 0.5)
				(thermal_bridge_width 0.5)
				(island_removal_mode 0)
			)
			(polygon
				(pts
					(xy 385.8514 0.381) (xy 386.3594 0.381) (xy 386.3594 0) (xy 385.8514 0)
				)
			)
		)
	)
	(footprint ""
		(layer "F.Cu")
		(at 411.130242 -47.682404 180)
		(property "Reference" "R25W61"
			(at -0.8382 -0.67818 180)
			(unlocked yes)
			(layer "F.SilkS")
			(effects
				(font
					(size 0.4064 0.254)
					(thickness 0.1524)
				)
				(justify left)
			)
		)
		(property "Value" ""
			(at 0 0 180)
			(layer "F.Fab")
			(effects
				(font
					(size 1.27 1.27)
				)
			)
		)
		(duplicate_pad_numbers_are_jumpers no)
		(fp_poly
			(pts
				(xy -0.2794 -0.1016) (xy 0.2794 -0.1016) (xy 0.2794 0.9906) (xy -0.2794 0.9906)
			)
			(stroke
				(width 0)
				(type default)
			)
			(fill no)
			(layer "F.CrtYd")
		)
		(fp_line
			(start 0.2794 0.9906)
			(end 0.2794 -0.1016)
			(stroke
				(width 0.1)
				(type default)
			)
			(layer "F.Fab")
		)
		(fp_line
			(start 0.2794 -0.1016)
			(end -0.2794 -0.1016)
			(stroke
				(width 0.1)
				(type default)
			)
			(layer "F.Fab")
		)
		(fp_line
			(start -0.2794 0.9906)
			(end 0.2794 0.9906)
			(stroke
				(width 0.1)
				(type default)
			)
			(layer "F.Fab")
		)
		(fp_line
			(start -0.2794 -0.1016)
			(end -0.2794 0.9906)
			(stroke
				(width 0.1)
				(type default)
			)
			(layer "F.Fab")
		)
		(pad "1" smd rect
			(at 0 0 180)
			(size 0.508 0.508)
			(layers "F.Cu" "F.Mask" "F.Paste")
			(net "CLK_100M_BMC_PE_R_DP")
		)
		(pad "2" smd rect
			(at 0 0.889 180)
			(size 0.508 0.508)
			(layers "F.Cu" "F.Mask" "F.Paste")
			(net "GND")
		)
		(zone
			(layer "F.Cu")
			(hatch none 0.5)
			(connect_pads
				(clearance 0)
			)
			(min_thickness 0.25)
			(keepout
				(tracks not_allowed)
				(vias allowed)
				(pads allowed)
				(copperpour not_allowed)
				(footprints allowed)
			)
			(placement
				(enabled no)
				(sheetname "")
			)
			(fill
				(thermal_gap 0.5)
				(thermal_bridge_width 0.5)
				(island_removal_mode 0)
			)
			(polygon
				(pts
					(xy 411.384242 -48.317404) (xy 410.876242 -48.317404) (xy 410.876242 -47.936404) (xy 411.384242 -47.936404)
				)
			)
		)
		(zone
			(layer "F.Cu")
			(hatch none 0.5)
			(connect_pads
				(clearance 0)
			)
			(min_thickness 0.25)
			(keepout
				(tracks allowed)
				(vias not_allowed)
				(pads allowed)
				(copperpour not_allowed)
				(footprints allowed)
			)
			(placement
				(enabled no)
				(sheetname "")
			)
			(fill
				(thermal_gap 0.5)
				(thermal_bridge_width 0.5)
				(island_removal_mode 0)
			)
			(polygon
				(pts
					(xy 411.384242 -47.936404) (xy 410.876242 -47.936404) (xy 410.876242 -48.317404) (xy 411.384242 -48.317404)
				)
			)
		)
	)
)
